(kicad_pcb
	(version 20241229)
	(generator "pcbnew")
	(generator_version "9.0")
	(general
		(thickness 1.711)
		(legacy_teardrops no)
	)
	(paper "A4")
	(title_block
		(title "Antmicro Baseboard for Jetson AGX Thor")
		(date "2026-02-18")
		(rev "1.1.0")
		(company "Antmicro Ltd")
		(comment 1 "www.antmicro.com")
		(comment 9 "footprints 267-268 of 1170")
	)
	(layers
		(0 "F.Cu" signal)
		(4 "In1.Cu" signal)
		(6 "In2.Cu" signal)
		(8 "In3.Cu" signal)
		(10 "In4.Cu" jumper)
		(12 "In5.Cu" signal)
		(14 "In6.Cu" signal)
		(16 "In7.Cu" signal)
		(18 "In8.Cu" signal)
		(2 "B.Cu" signal)
		(9 "F.Adhes" user "F.Adhesive")
		(11 "B.Adhes" user "B.Adhesive")
		(13 "F.Paste" user)
		(15 "B.Paste" user)
		(5 "F.SilkS" user "F.Silkscreen")
		(7 "B.SilkS" user "B.Silkscreen")
		(1 "F.Mask" user)
		(3 "B.Mask" user)
		(17 "Dwgs.User" user "User.Drawings")
		(19 "Cmts.User" user "User.Comments")
		(21 "Eco1.User" user "User.Eco1")
		(23 "Eco2.User" user "User.Eco2")
		(25 "Edge.Cuts" user)
		(27 "Margin" user)
		(31 "F.CrtYd" user "F.Courtyard")
		(29 "B.CrtYd" user "B.Courtyard")
		(35 "F.Fab" user)
		(33 "B.Fab" user)
	)
	(footprint "antmicro-footprints:MLP44-24L_4x4x0.75mm"
		(layer "F.Cu")
		(at 179.7 70.45)
		(property "Reference" "U65"
			(at -3.36 0.73 90)
			(layer "F.SilkS")
			(effects
				(font
					(size 0.7 0.7)
					(thickness 0.15)
				)
				(justify right top)
			)
		)
		(property "Value" "SIC437AED-T1-GE3"
			(at -2.7 3.6 0)
			(layer "F.Fab")
			(effects
				(font
					(size 0.7 0.7)
					(thickness 0.15)
				)
				(justify left bottom)
			)
		)
		(property "Datasheet" "https://www.vishay.com/docs/75921/sic437.pdf"
			(at 0 0 0)
			(layer "F.Fab")
			(hide yes)
			(effects
				(font
					(size 1.27 1.27)
					(thickness 0.15)
				)
			)
		)
		(property "Description" "DC/DC Buck Step Down Regulator Adjustable, 4.5-28V In, 0.6V to 20V/12A Out, 1MHz, PowerPAK MLP44-24"
			(at 0 0 0)
			(layer "F.Fab")
			(hide yes)
			(effects
				(font
					(size 1.27 1.27)
					(thickness 0.15)
				)
			)
		)
		(property "Manufacturer" "Vishay"
			(at 0 0 0)
			(unlocked yes)
			(layer "F.Fab")
			(hide yes)
			(effects
				(font
					(size 1 1)
					(thickness 0.15)
				)
			)
		)
		(property "MPN" "SIC437AED-T1-GE3"
			(at 0 0 0)
			(unlocked yes)
			(layer "F.Fab")
			(hide yes)
			(effects
				(font
					(size 1 1)
					(thickness 0.15)
				)
			)
		)
		(property "Author" "Antmicro"
			(at 0 0 0)
			(unlocked yes)
			(layer "F.Fab")
			(hide yes)
			(effects
				(font
					(size 1 1)
					(thickness 0.15)
				)
			)
		)
		(property "License" "Apache-2.0"
			(at 0 0 0)
			(unlocked yes)
			(layer "F.Fab")
			(hide yes)
			(effects
				(font
					(size 1 1)
					(thickness 0.15)
				)
			)
		)
		(component_classes
			(class "DCDC_20V")
		)
		(sheetname "/DCDC/")
		(sheetfile "dcdc.kicad_sch")
		(attr smd)
		(net_tie_pad_groups "1,2,26" "3,4,27" "5,6,7,8,9")
		(fp_line
			(start -2.11 -1.38)
			(end -2.11 -2.1)
			(stroke
				(width 0.15)
				(type solid)
			)
			(layer "F.SilkS")
		)
		(fp_line
			(start -2.11 2.11)
			(end -2.11 1.39)
			(stroke
				(width 0.15)
				(type solid)
			)
			(layer "F.SilkS")
		)
		(fp_line
			(start -1.89 -2.1)
			(end -2.11 -2.1)
			(stroke
				(width 0.15)
				(type solid)
			)
			(layer "F.SilkS")
		)
		(fp_line
			(start -1.89 2.11)
			(end -2.11 2.11)
			(stroke
				(width 0.15)
				(type solid)
			)
			(layer "F.SilkS")
		)
		(fp_line
			(start 1.44 2.11)
			(end 2.11 2.11)
			(stroke
				(width 0.15)
				(type solid)
			)
			(layer "F.SilkS")
		)
		(fp_line
			(start 1.89 -2.11)
			(end 2.11 -2.11)
			(stroke
				(width 0.15)
				(type solid)
			)
			(layer "F.SilkS")
		)
		(fp_line
			(start 2.11 -2.11)
			(end 2.11 -1.69)
			(stroke
				(width 0.15)
				(type solid)
			)
			(layer "F.SilkS")
		)
		(fp_line
			(start 2.11 2.11)
			(end 2.11 1.84)
			(stroke
				(width 0.15)
				(type solid)
			)
			(layer "F.SilkS")
		)
		(fp_circle
			(center -2.25 -1.15)
			(end -2.2 -1.15)
			(stroke
				(width 0.15)
				(type solid)
			)
			(fill yes)
			(layer "F.SilkS")
		)
		(fp_line
			(start -2.55 -2.55)
			(end 2.55 -2.55)
			(stroke
				(width 0.05)
				(type solid)
			)
			(layer "F.CrtYd")
		)
		(fp_line
			(start -2.55 2.55)
			(end -2.55 -2.55)
			(stroke
				(width 0.05)
				(type solid)
			)
			(layer "F.CrtYd")
		)
		(fp_line
			(start 2.55 -2.55)
			(end 2.55 2.55)
			(stroke
				(width 0.05)
				(type solid)
			)
			(layer "F.CrtYd")
		)
		(fp_line
			(start 2.55 2.55)
			(end -2.55 2.55)
			(stroke
				(width 0.05)
				(type solid)
			)
			(layer "F.CrtYd")
		)
		(fp_line
			(start -2 -1)
			(end -2 2)
			(stroke
				(width 0.15)
				(type solid)
			)
			(layer "F.Fab")
		)
		(fp_line
			(start -2 2)
			(end 2 2)
			(stroke
				(width 0.15)
				(type solid)
			)
			(layer "F.Fab")
		)
		(fp_line
			(start -1 -2)
			(end -2 -1)
			(stroke
				(width 0.15)
				(type solid)
			)
			(layer "F.Fab")
		)
		(fp_line
			(start 2 -2)
			(end -1 -2)
			(stroke
				(width 0.15)
				(type solid)
			)
			(layer "F.Fab")
		)
		(fp_line
			(start 2 2)
			(end 2 -2)
			(stroke
				(width 0.15)
				(type solid)
			)
			(layer "F.Fab")
		)
		(fp_text user "Author: Antmicro"
			(at -2.7 8 0)
			(layer "F.Fab")
			(effects
				(font
					(size 0.7 0.7)
					(thickness 0.15)
				)
				(justify left bottom)
			)
		)
		(fp_text user "License: Apache-2.0"
			(at -2.7 5.6 0)
			(layer "F.Fab")
			(effects
				(font
					(size 0.7 0.7)
					(thickness 0.15)
				)
				(justify left bottom)
			)
		)
		(fp_text user "${REFERENCE}"
			(at -2.7 6.8 0)
			(layer "F.Fab")
			(effects
				(font
					(size 0.7 0.7)
					(thickness 0.15)
				)
				(justify left bottom)
			)
		)
		(pad "1" smd roundrect
			(at -1.94 -0.825 90)
			(size 0.3 0.725)
			(layers "F.Cu" "F.Mask" "F.Paste")
			(roundrect_rratio 0.25)
			(net 13 "VCC")
			(pinfunction "V_{IN}")
			(pintype "power_in")
		)
		(pad "2" smd roundrect
			(at -1.94 -0.375 90)
			(size 0.3 0.725)
			(layers "F.Cu" "F.Mask" "F.Paste")
			(roundrect_rratio 0.25)
			(net 13 "VCC")
			(pinfunction "V_{IN}")
			(pintype "passive")
		)
		(pad "3" smd roundrect
			(at -1.94 0.525 90)
			(size 0.3 0.725)
			(layers "F.Cu" "F.Mask" "F.Paste")
			(roundrect_rratio 0.25)
			(net 1 "GND")
			(pinfunction "P_{GND}")
			(pintype "passive")
		)
		(pad "4" smd roundrect
			(at -1.94 0.975 90)
			(size 0.3 0.725)
			(layers "F.Cu" "F.Mask" "F.Paste")
			(roundrect_rratio 0.25)
			(net 1 "GND")
			(pinfunction "P_{GND}")
			(pintype "passive")
		)
		(pad "5" smd custom
			(at -1.475 1.94)
			(size 0.3 0.3)
			(layers "F.Cu" "F.Mask" "F.Paste")
			(net 1184 "/DCDC/20V_SW")
			(pinfunction "SW")
			(pintype "passive")
			(options
				(clearance outline)
				(anchor circle)
			)
			(primitives
				(gr_poly
					(pts
						(xy -0.15 -0.2875) (xy -0.144291 -0.316201) (xy -0.128033 -0.340533) (xy -0.103701 -0.356791)
						(xy -0.075 -0.3625) (xy 0.075 -0.3625) (xy 0.103701 -0.356791) (xy 0.128033 -0.340533) (xy 0.144291 -0.316201)
						(xy 0.15 -0.2875) (xy 0.15 0.2875) (xy 0.144291 0.316201) (xy 0.128033 0.340533) (xy 0.103701 0.356791)
						(xy 0.075 0.3625) (xy -0.075 0.3625) (xy -0.103701 0.356791) (xy -0.128033 0.340533) (xy -0.144291 0.316201)
						(xy -0.15 0.2875)
					)
					(width 0)
					(fill yes)
				)
				(gr_poly
					(pts
						(xy -0.15 -0.3625) (xy 2.2 -0.3625) (xy 2.2 -0.0875) (xy -0.15 -0.0875)
					)
					(width 0)
					(fill yes)
				)
			)
		)
		(pad "6" smd roundrect
			(at -1.025 1.94)
			(size 0.3 0.725)
			(layers "F.Cu" "F.Mask" "F.Paste")
			(roundrect_rratio 0.25)
			(net 1184 "/DCDC/20V_SW")
			(pinfunction "SW")
			(pintype "passive")
		)
		(pad "7" smd roundrect
			(at -0.575 1.94)
			(size 0.3 0.725)
			(layers "F.Cu" "F.Mask" "F.Paste")
			(roundrect_rratio 0.25)
			(net 1184 "/DCDC/20V_SW")
			(pinfunction "SW")
			(pintype "passive")
		)
		(pad "8" smd roundrect
			(at 0.125 1.94)
			(size 0.3 0.725)
			(layers "F.Cu" "F.Mask" "F.Paste")
			(roundrect_rratio 0.25)
			(net 1184 "/DCDC/20V_SW")
			(pinfunction "SW")
			(pintype "passive")
		)
		(pad "9" smd roundrect
			(at 0.575 1.94)
			(size 0.3 0.725)
			(layers "F.Cu" "F.Mask" "F.Paste")
			(roundrect_rratio 0.25)
			(net 1184 "/DCDC/20V_SW")
			(pinfunction "SW")
			(pintype "passive")
		)
		(pad "10" smd roundrect
			(at 1.025 1.935)
			(size 0.3 0.725)
			(layers "F.Cu" "F.Mask" "F.Paste")
			(roundrect_rratio 0.25)
			(net 1231 "unconnected-(U65-GL-Pad10)_2")
			(pinfunction "GL")
			(pintype "passive+no_connect")
		)
		(pad "11" smd roundrect
			(at 1.94 1.425 90)
			(size 0.3 0.725)
			(layers "F.Cu" "F.Mask" "F.Paste")
			(roundrect_rratio 0.25)
			(net 1230 "unconnected-(U65-GL-Pad10)_1")
			(pinfunction "GL")
			(pintype "passive+no_connect")
		)
		(pad "12" smd roundrect
			(at 1.94 0.975 90)
			(size 0.3 0.725)
			(layers "F.Cu" "F.Mask" "F.Paste")
			(roundrect_rratio 0.25)
			(net 1081 "/DCDC/20V_VDRV")
			(pinfunction "V_{DRV}")
			(pintype "passive")
		)
		(pad "13" smd roundrect
			(at 1.94 0.525 90)
			(size 0.3 0.725)
			(layers "F.Cu" "F.Mask" "F.Paste")
			(roundrect_rratio 0.25)
			(net 1 "GND")
			(pinfunction "P_{GND}")
			(pintype "power_in")
		)
		(pad "14" smd roundrect
			(at 1.94 0.075 90)
			(size 0.3 0.725)
			(layers "F.Cu" "F.Mask" "F.Paste")
			(roundrect_rratio 0.25)
			(net 1228 "unconnected-(U65-P_{GOOD}-Pad14)")
			(pinfunction "P_{GOOD}")
			(pintype "output+no_connect")
		)
		(pad "15" smd roundrect
			(at 1.94 -0.375 90)
			(size 0.3 0.725)
			(layers "F.Cu" "F.Mask" "F.Paste")
			(roundrect_rratio 0.25)
			(net 905 "/DCDC/20V_VDD")
			(pinfunction "V_{DD}")
			(pintype "passive")
		)
		(pad "16" smd roundrect
			(at 1.94 -0.825 90)
			(size 0.3 0.725)
			(layers "F.Cu" "F.Mask" "F.Paste")
			(roundrect_rratio 0.25)
			(net 1 "GND")
			(pinfunction "A_{GND}")
			(pintype "power_in")
		)
		(pad "17" smd roundrect
			(at 1.94 -1.275 90)
			(size 0.3 0.725)
			(layers "F.Cu" "F.Mask" "F.Paste")
			(roundrect_rratio 0.25)
			(net 1220 "/DCDC/20V_FB")
			(pinfunction "FB")
			(pintype "passive")
		)
		(pad "18" smd roundrect
			(at 1.475 -1.94)
			(size 0.3 0.725)
			(layers "F.Cu" "F.Mask" "F.Paste")
			(roundrect_rratio 0.25)
			(net 1105 "/DCDC/20V_OUT")
			(pinfunction "V_{OUT}")
			(pintype "passive")
		)
		(pad "19" smd roundrect
			(at 1.025 -1.94)
			(size 0.3 0.725)
			(layers "F.Cu" "F.Mask" "F.Paste")
			(roundrect_rratio 0.25)
			(net 1211 "/DCDC/20V_EN")
			(pinfunction "EN")
			(pintype "input")
		)
		(pad "20" smd roundrect
			(at 0.575 -1.94)
			(size 0.3 0.725)
			(layers "F.Cu" "F.Mask" "F.Paste")
			(roundrect_rratio 0.25)
			(net 1210 "/DCDC/20V_MODE2")
			(pinfunction "MODE2")
			(pintype "input")
		)
		(pad "21" smd roundrect
			(at 0.125 -1.94)
			(size 0.3 0.725)
			(layers "F.Cu" "F.Mask" "F.Paste")
			(roundrect_rratio 0.25)
			(net 1208 "/DCDC/20V_MODE1")
			(pinfunction "MODE1")
			(pintype "input")
		)
		(pad "22" smd roundrect
			(at -0.575 -1.94)
			(size 0.3 0.725)
			(layers "F.Cu" "F.Mask" "F.Paste")
			(roundrect_rratio 0.25)
			(net 13 "VCC")
			(pinfunction "V_{IN}")
			(pintype "passive")
		)
		(pad "23" smd roundrect
			(at -1.025 -1.94)
			(size 0.3 0.725)
			(layers "F.Cu" "F.Mask" "F.Paste")
			(roundrect_rratio 0.25)
			(net 1086 "/DCDC/20V_BOOT")
			(pinfunction "BOOT")
			(pintype "passive")
		)
		(pad "24" smd roundrect
			(at -1.475 -1.94)
			(size 0.3 0.725)
			(layers "F.Cu" "F.Mask" "F.Paste")
			(roundrect_rratio 0.25)
			(net 1104 "/DCDC/20V_PHASE")
			(pinfunction "PHASE")
			(pintype "passive")
		)
		(pad "25" smd rect
			(at 0.49 -0.75 180)
			(size 1.575 1.05)
			(layers "F.Cu" "F.Mask" "F.Paste")
			(net 1 "GND")
			(pinfunction "A_{GND}")
			(pintype "passive")
		)
		(pad "26" smd rect
			(at -1.175 -0.75 180)
			(size 1.15 1.05)
			(layers "F.Cu" "F.Mask" "F.Paste")
			(net 13 "VCC")
			(pinfunction "V_{IN}")
			(pintype "passive")
		)
		(pad "27" smd custom
			(at -0.75 0.775)
			(size 1 1)
			(layers "F.Cu" "F.Mask" "F.Paste")
			(net 1 "GND")
			(pinfunction "P_{GND}")
			(pintype "passive")
			(options
				(clearance outline)
				(anchor rect)
			)
			(primitives
				(gr_poly
					(pts
						(xy -1 0.5) (xy -1 -0.7) (xy 1.825 -0.7) (xy 1.825 -0.245) (xy 1.175 -0.245) (xy 1.175 0.5)
					)
					(width 0)
					(fill yes)
				)
			)
		)
		(pad "28" smd rect
			(at 0.985 0.99 180)
			(size 0.58 0.38)
			(layers "F.Cu" "F.Mask" "F.Paste")
			(net 1229 "unconnected-(U65-GL-Pad10)")
			(pinfunction "GL")
			(pintype "passive+no_connect")
		)
	)
	(footprint "antmicro-footprints:C_0402_1005Metric"
		(layer "F.Cu")
		(at 184.044468 127.21 -90)
		(descr "Capacitor SMD 0402")
		(tags "capacitor SMD 0402")
		(property "Reference" "C53"
			(at -1.11 -0.555532 90)
			(layer "F.SilkS")
			(effects
				(font
					(size 0.7 0.7)
					(thickness 0.15)
				)
				(justify right top)
			)
		)
		(property "Value" "C_1u_0402"
			(at -1.022927 2.155213 90)
			(layer "F.Fab")
			(effects
				(font
					(size 0.7 0.7)
					(thickness 0.15)
				)
				(justify right top)
			)
		)
		(property "Datasheet" "https://product.tdk.com/en/search/capacitor/ceramic/mlcc/info?part_no=C1005X6S1A105K050BC"
			(at 0 0 90)
			(layer "F.Fab")
			(hide yes)
			(effects
				(font
					(size 1.27 1.27)
					(thickness 0.15)
				)
			)
		)
		(property "Description" "SMD Multilayer Ceramic Capacitor, 1 µF, 10 V, 0402 [1005 Metric], ± 10%, X6S, C"
			(at 0 0 90)
			(layer "F.Fab")
			(hide yes)
			(effects
				(font
					(size 1.27 1.27)
					(thickness 0.15)
				)
			)
		)
		(property "Manufacturer" "TDK"
			(at 0 0 270)
			(unlocked yes)
			(layer "F.Fab")
			(hide yes)
			(effects
				(font
					(size 1 1)
					(thickness 0.15)
				)
			)
		)
		(property "MPN" "C1005X6S1A105K050BC"
			(at 0 0 270)
			(unlocked yes)
			(layer "F.Fab")
			(hide yes)
			(effects
				(font
					(size 1 1)
					(thickness 0.15)
				)
			)
		)
		(property "Val" "1u"
			(at 0 0 270)
			(unlocked yes)
			(layer "F.Fab")
			(hide yes)
			(effects
				(font
					(size 1 1)
					(thickness 0.15)
				)
			)
		)
		(property "License" "Apache-2.0"
			(at 0 0 270)
			(unlocked yes)
			(layer "F.Fab")
			(hide yes)
			(effects
				(font
					(size 1 1)
					(thickness 0.15)
				)
			)
		)
		(property "Author" "Antmicro"
			(at 0 0 270)
			(unlocked yes)
			(layer "F.Fab")
			(hide yes)
			(effects
				(font
					(size 1 1)
					(thickness 0.15)
				)
			)
		)
		(property "Voltage" ""
			(at 0 0 270)
			(unlocked yes)
			(layer "F.Fab")
			(hide yes)
			(effects
				(font
					(size 1 1)
					(thickness 0.15)
				)
			)
		)
		(property "Dielectric" ""
			(at 0 0 270)
			(unlocked yes)
			(layer "F.Fab")
			(hide yes)
			(effects
				(font
					(size 1 1)
					(thickness 0.15)
				)
			)
		)
		(sheetname "/DCDC/")
		(sheetfile "dcdc.kicad_sch")
		(attr smd)
		(fp_rect
			(start -0.925 -0.47)
			(end 0.925 0.47)
			(stroke
				(width 0.05)
				(type default)
			)
			(fill no)
			(layer "F.CrtYd")
		)
		(fp_line
			(start -0.494 0.248)
			(end -0.494 -0.25)
			(stroke
				(width 0.15)
				(type solid)
			)
			(layer "F.Fab")
		)
		(fp_line
			(start 0.504 0.248)
			(end -0.494 0.248)
			(stroke
				(width 0.15)
				(type solid)
			)
			(layer "F.Fab")
		)
		(fp_line
			(start -0.494 -0.25)
			(end 0.504 -0.25)
			(stroke
				(width 0.15)
				(type solid)
			)
			(layer "F.Fab")
		)
		(fp_line
			(start 0.504 -0.25)
			(end 0.504 0.248)
			(stroke
				(width 0.15)
				(type solid)
			)
			(layer "F.Fab")
		)
		(fp_text user "Author: Antmicro"
			(at -0.939 3.399 90)
			(layer "F.Fab")
			(effects
				(font
					(size 0.7 0.7)
					(thickness 0.15)
				)
				(justify right top)
			)
		)
		(fp_text user "License: Apache-2.0"
			(at -0.939 5.799 90)
			(layer "F.Fab")
			(effects
				(font
					(size 0.7 0.7)
					(thickness 0.15)
				)
				(justify right top)
			)
		)
		(fp_text user "${REFERENCE}"
			(at -0.939 4.599 90)
			(layer "F.Fab")
			(effects
				(font
					(size 0.7 0.7)
					(thickness 0.15)
				)
				(justify right top)
			)
		)
		(pad "1" smd roundrect
			(at -0.48 0 270)
			(size 0.59 0.64)
			(layers "F.Cu" "F.Mask" "F.Paste")
			(roundrect_rratio 0.25)
			(net 1 "GND")
			(pintype "passive")
		)
		(pad "2" smd roundrect
			(at 0.48 0 270)
			(size 0.59 0.64)
			(layers "F.Cu" "F.Mask" "F.Paste")
			(roundrect_rratio 0.25)
			(net 19 "/DCDC/3V3_VDD")
			(pintype "passive")
		)
	)
)
